# S9S_MB_2U (Grand Teton) — schematic netlist excerpt (pin names and nets, part order shuffled) for the footprints in the layout excerpt that follows; sources: Cadence DE-HDL packaged netlist, KiCad conversion of 03242023_DA0F0TMBIJ0_F0T_Motherboard_J_brd_V01_OCP.brd

PR2530  Q_RES  10 1% EMPTY  pkg 0402LF  page 304 : A = P12V_HSC_GATE_G3 ; B = P12V_HSC_GATE2

U176  LTC4307CMS8  EMPTY  pkg MSOP8  page 234
  ENABLE  = SMB_BMC_SWB_EN_R2
  SCL_OUT  = I3C_BMC_SWB_BUF_R_SCL
  SCL_IN  = I3C_BMC_SWB_R_SCL
  GND  = GND
  READY  = NC
  SDA_IN  = I3C_BMC_SWB_R_SDA
  SDA_OUT  = I3C_BMC_SWB_BUF_R_SDA
  VCC  = P3V3_AUX

(kicad_pcb
	(version 20260206)
	(generator "pcbnew")
	(generator_version "10.0")
	(general
		(thickness 1.6)
		(legacy_teardrops no)
	)
	(paper "A4")
	(title_block
		(title "03242023_DA0F0TMBIJ0_F0T_Motherboard_J_brd_V01_OCP.brd")
		(comment 1 "Grand Teton / footprints 208-209 of 6105")
	)
	(layers
		(0 "F.Cu" signal "TOP")
		(4 "In1.Cu" signal "GND")
		(6 "In2.Cu" signal "IN1")
		(8 "In3.Cu" signal "GND1")
		(10 "In4.Cu" signal "IN2")
		(12 "In5.Cu" signal "GND2")
		(14 "In6.Cu" signal "IN3")
		(16 "In7.Cu" signal "GND3")
		(18 "In8.Cu" signal "VCC")
		(20 "In9.Cu" signal "VCC1")
		(22 "In10.Cu" signal "GND4")
		(24 "In11.Cu" signal "IN4")
		(26 "In12.Cu" signal "GND5")
		(28 "In13.Cu" signal "IN5")
		(30 "In14.Cu" signal "GND6")
		(32 "In15.Cu" signal "IN6")
		(34 "In16.Cu" signal "GND7")
		(2 "B.Cu" signal "BOTTOM")
		(9 "F.Adhes" user "F.Adhesive")
		(11 "B.Adhes" user "B.Adhesive")
		(13 "F.Paste" user "Package Geometry/Pastemask Top")
		(15 "B.Paste" user "Package Geometry/Pastemask Bottom")
		(5 "F.SilkS" user "Ref Des/Silkscreen Top")
		(7 "B.SilkS" user "Ref Des/Silkscreen Bottom")
		(1 "F.Mask" user "Board Geometry/Soldermask Top")
		(3 "B.Mask" user "Board Geometry/Soldermask Bottom")
		(17 "Dwgs.User" user "User.Drawings")
		(19 "Cmts.User" user "User.Comments")
		(21 "Eco1.User" user "User.Eco1")
		(23 "Eco2.User" user "User.Eco2")
		(25 "Edge.Cuts" user "Board Geometry/Outline")
		(27 "Margin" user)
		(31 "F.CrtYd" user "Package Geometry/Place Bound Top")
		(29 "B.CrtYd" user "Package Geometry/Place Bound Bottom")
		(35 "F.Fab" user "Ref Des/Assembly Top")
		(33 "B.Fab" user "Ref Des/Assembly Bottom")
	)
	(footprint ""
		(layer "F.Cu")
		(at 268.336522 -394.17117)
		(property "Reference" "PR2530"
			(at 0 0 0)
			(layer "F.SilkS")
			(hide yes)
			(effects
				(font
					(size 1.27 1.27)
				)
			)
		)
		(property "Value" ""
			(at 0 0 0)
			(layer "F.Fab")
			(effects
				(font
					(size 1.27 1.27)
				)
			)
		)
		(duplicate_pad_numbers_are_jumpers no)
		(fp_line
			(start -0.7874 -0.4064)
			(end 0.7874 -0.4064)
			(stroke
				(width 0.1524)
				(type default)
			)
			(layer "F.SilkS")
		)
		(fp_line
			(start -0.7874 0.4064)
			(end -0.7874 -0.4064)
			(stroke
				(width 0.1524)
				(type default)
			)
			(layer "F.SilkS")
		)
		(fp_line
			(start 0.7874 -0.4064)
			(end 0.7874 0.4064)
			(stroke
				(width 0.1524)
				(type default)
			)
			(layer "F.SilkS")
		)
		(fp_line
			(start 0.7874 0.4064)
			(end -0.7874 0.4064)
			(stroke
				(width 0.1524)
				(type default)
			)
			(layer "F.SilkS")
		)
		(fp_line
			(start -0.67945 -0.305054)
			(end -0.12065 -0.305054)
			(stroke
				(width 0.1)
				(type default)
			)
			(layer "F.Fab")
		)
		(fp_line
			(start -0.67945 0.3048)
			(end -0.67945 -0.305054)
			(stroke
				(width 0.1)
				(type default)
			)
			(layer "F.Fab")
		)
		(fp_line
			(start -0.12065 -0.305054)
			(end -0.12065 -0.2794)
			(stroke
				(width 0.1)
				(type default)
			)
			(layer "F.Fab")
		)
		(fp_line
			(start -0.12065 -0.2794)
			(end 0.12065 -0.2794)
			(stroke
				(width 0.1)
				(type default)
			)
			(layer "F.Fab")
		)
		(fp_line
			(start -0.12065 0.2794)
			(end -0.12065 0.3048)
			(stroke
				(width 0.1)
				(type default)
			)
			(layer "F.Fab")
		)
		(fp_line
			(start -0.12065 0.3048)
			(end -0.67945 0.3048)
			(stroke
				(width 0.1)
				(type default)
			)
			(layer "F.Fab")
		)
		(fp_line
			(start 0.120396 0.2794)
			(end -0.12065 0.2794)
			(stroke
				(width 0.1)
				(type default)
			)
			(layer "F.Fab")
		)
		(fp_line
			(start 0.120396 0.3048)
			(end 0.120396 0.2794)
			(stroke
				(width 0.1)
				(type default)
			)
			(layer "F.Fab")
		)
		(fp_line
			(start 0.12065 -0.3048)
			(end 0.67945 -0.3048)
			(stroke
				(width 0.1)
				(type default)
			)
			(layer "F.Fab")
		)
		(fp_line
			(start 0.12065 -0.2794)
			(end 0.12065 -0.3048)
			(stroke
				(width 0.1)
				(type default)
			)
			(layer "F.Fab")
		)
		(fp_line
			(start 0.67945 -0.3048)
			(end 0.67945 0.3048)
			(stroke
				(width 0.1)
				(type default)
			)
			(layer "F.Fab")
		)
		(fp_line
			(start 0.67945 0.3048)
			(end 0.120396 0.3048)
			(stroke
				(width 0.1)
				(type default)
			)
			(layer "F.Fab")
		)
		(pad "1" smd circle
			(at -0.40005 0)
			(size 0 0)
			(layers "F.Cu" "F.Mask" "F.Paste")
			(net "P12V_HSC_GATE_G3")
		)
		(pad "2" smd circle
			(at 0.40005 0)
			(size 0 0)
			(layers "F.Cu" "F.Mask" "F.Paste")
			(net "P12V_HSC_GATE2")
		)
	)
	(footprint ""
		(layer "F.Cu")
		(at 363.556042 -397.959834)
		(property "Reference" "U176"
			(at -0.112522 -2.236724 0)
			(unlocked yes)
			(layer "F.SilkS")
			(effects
				(font
					(size 0.7874 0.5842)
					(thickness 0.1524)
				)
				(justify left)
			)
		)
		(property "Value" ""
			(at 0 0 0)
			(layer "F.Fab")
			(effects
				(font
					(size 1.27 1.27)
				)
			)
		)
		(duplicate_pad_numbers_are_jumpers no)
		(fp_line
			(start -1.3716 -1.524)
			(end -0.508 -1.524)
			(stroke
				(width 0.1524)
				(type default)
			)
			(layer "F.SilkS")
		)
		(fp_line
			(start -1.3716 1.524)
			(end -1.3716 -1.524)
			(stroke
				(width 0.1524)
				(type default)
			)
			(layer "F.SilkS")
		)
		(fp_line
			(start -0.508 -1.524)
			(end 0 -1.016)
			(stroke
				(width 0.1524)
				(type default)
			)
			(layer "F.SilkS")
		)
		(fp_line
			(start 0 -1.016)
			(end 0.508 -1.524)
			(stroke
				(width 0.1524)
				(type default)
			)
			(layer "F.SilkS")
		)
		(fp_line
			(start 0.508 -1.524)
			(end 1.3716 -1.524)
			(stroke
				(width 0.1524)
				(type default)
			)
			(layer "F.SilkS")
		)
		(fp_line
			(start 1.3716 -1.524)
			(end 1.3716 1.524)
			(stroke
				(width 0.1524)
				(type default)
			)
			(layer "F.SilkS")
		)
		(fp_line
			(start 1.3716 1.524)
			(end -1.3716 1.524)
			(stroke
				(width 0.1524)
				(type default)
			)
			(layer "F.SilkS")
		)
		(fp_poly
			(pts
				(xy -1.457452 -2.04724) (xy -1.78562 -1.49352) (xy -2.082292 -2.04724)
			)
			(stroke
				(width 0)
				(type default)
			)
			(fill yes)
			(layer "F.SilkS")
		)
		(fp_line
			(start -2.54 -1.0668)
			(end -1.5494 -1.0668)
			(stroke
				(width 0.1)
				(type default)
			)
			(layer "F.Fab")
		)
		(fp_line
			(start -2.54 1.0668)
			(end -2.54 -1.0668)
			(stroke
				(width 0.1)
				(type default)
			)
			(layer "F.Fab")
		)
		(fp_line
			(start -1.5494 -1.524)
			(end 1.5494 -1.524)
			(stroke
				(width 0.1)
				(type default)
			)
			(layer "F.Fab")
		)
		(fp_line
			(start -1.5494 -1.0668)
			(end -1.5494 -1.524)
			(stroke
				(width 0.1)
				(type default)
			)
			(layer "F.Fab")
		)
		(fp_line
			(start -1.5494 1.0668)
			(end -2.54 1.0668)
			(stroke
				(width 0.1)
				(type default)
			)
			(layer "F.Fab")
		)
		(fp_line
			(start -1.5494 1.0668)
			(end -1.5494 -1.0668)
			(stroke
				(width 0.1)
				(type default)
			)
			(layer "F.Fab")
		)
		(fp_line
			(start -1.5494 1.524)
			(end -1.5494 1.0668)
			(stroke
				(width 0.1)
				(type default)
			)
			(layer "F.Fab")
		)
		(fp_line
			(start 1.5494 -1.524)
			(end 1.5494 -1.0668)
			(stroke
				(width 0.1)
				(type default)
			)
			(layer "F.Fab")
		)
		(fp_line
			(start 1.5494 -1.0668)
			(end 1.5494 1.0668)
			(stroke
				(width 0.1)
				(type default)
			)
			(layer "F.Fab")
		)
		(fp_line
			(start 1.5494 -1.0668)
			(end 2.54 -1.0668)
			(stroke
				(width 0.1)
				(type default)
			)
			(layer "F.Fab")
		)
		(fp_line
			(start 1.5494 1.0668)
			(end 1.5494 1.524)
			(stroke
				(width 0.1)
				(type default)
			)
			(layer "F.Fab")
		)
		(fp_line
			(start 1.5494 1.524)
			(end -1.5494 1.524)
			(stroke
				(width 0.1)
				(type default)
			)
			(layer "F.Fab")
		)
		(fp_line
			(start 2.54 -1.0668)
			(end 2.54 1.0668)
			(stroke
				(width 0.1)
				(type default)
			)
			(layer "F.Fab")
		)
		(fp_line
			(start 2.54 1.0668)
			(end 1.5494 1.0668)
			(stroke
				(width 0.1)
				(type default)
			)
			(layer "F.Fab")
		)
		(fp_poly
			(pts
				(xy -3.60172 -0.719328) (xy -3.60172 -1.344168) (xy -3.048 -1.016)
			)
			(stroke
				(width 0)
				(type default)
			)
			(fill yes)
			(layer "F.Fab")
		)
		(pad "1" smd rect
			(at -2.232406 -0.975106 270)
			(size 0.3556 1.4224)
			(layers "F.Cu" "F.Mask" "F.Paste")
			(net "SMB_BMC_SWB_EN_R2")
		)
		(pad "2" smd rect
			(at -2.232406 -0.32512 270)
			(size 0.3556 1.4224)
			(layers "F.Cu" "F.Mask" "F.Paste")
			(net "I3C_BMC_SWB_BUF_R_SCL")
		)
		(pad "3" smd rect
			(at -2.232406 0.32512 270)
			(size 0.3556 1.4224)
			(layers "F.Cu" "F.Mask" "F.Paste")
			(net "I3C_BMC_SWB_R_SCL")
		)
		(pad "4" smd rect
			(at -2.232406 0.975106 270)
			(size 0.3556 1.4224)
			(layers "F.Cu" "F.Mask" "F.Paste")
			(net "GND")
		)
		(pad "5" smd rect
			(at 2.232406 0.975106 270)
			(size 0.3556 1.4224)
			(layers "F.Cu" "F.Mask" "F.Paste")
			(net "Net_8615")
		)
		(pad "6" smd rect
			(at 2.232406 0.32512 270)
			(size 0.3556 1.4224)
			(layers "F.Cu" "F.Mask" "F.Paste")
			(net "I3C_BMC_SWB_R_SDA")
		)
		(pad "7" smd rect
			(at 2.232406 -0.32512 270)
			(size 0.3556 1.4224)
			(layers "F.Cu" "F.Mask" "F.Paste")
			(net "I3C_BMC_SWB_BUF_R_SDA")
		)
		(pad "8" smd rect
			(at 2.232406 -0.975106 270)
			(size 0.3556 1.4224)
			(layers "F.Cu" "F.Mask" "F.Paste")
			(net "P3V3_AUX")
		)
	)
)
